# T6G (Grand Teton) — schematic netlist excerpt (pin names and nets, part order shuffled) for the footprints in the layout excerpt that follows; sources: Cadence DE-HDL packaged netlist, KiCad conversion of 04192023_DAF0TMB3IC0_F0TG_MB_C_brd_V02_OCP.brd

R627  Q_RES  51.1 1% EMPTY  pkg 0201LF  page 320 : A = CLK_100M_RETIMER_CPU1_P0_DN ; B = GND
R6862  Q_RES  33 5% CHIP  pkg 0402LF  page 151 : A = SMB_HOST_CLK_3V3AUX_SCL_R1 ; B = SMB_9ZXL045_P1_SCL

(kicad_pcb
	(version 20260206)
	(generator "pcbnew")
	(generator_version "10.0")
	(general
		(thickness 1.6)
		(legacy_teardrops no)
	)
	(paper "A4")
	(title_block
		(title "04192023_DAF0TMB3IC0_F0TG_MB_C_brd_V02_OCP.brd")
		(comment 1 "Grand Teton / footprints 3884-3885 of 8354")
	)
	(layers
		(0 "F.Cu" signal "TOP")
		(4 "In1.Cu" signal "GND")
		(6 "In2.Cu" signal "IN1")
		(8 "In3.Cu" signal "GND1")
		(10 "In4.Cu" signal "IN2")
		(12 "In5.Cu" signal "GND2")
		(14 "In6.Cu" signal "IN3")
		(16 "In7.Cu" signal "GND3")
		(18 "In8.Cu" signal "VCC")
		(20 "In9.Cu" signal "VCC1")
		(22 "In10.Cu" signal "GND4")
		(24 "In11.Cu" signal "IN4")
		(26 "In12.Cu" signal "GND5")
		(28 "In13.Cu" signal "IN5")
		(30 "In14.Cu" signal "GND6")
		(32 "In15.Cu" signal "IN6")
		(34 "In16.Cu" signal "GND7")
		(2 "B.Cu" signal "BOTTOM")
		(9 "F.Adhes" user "F.Adhesive")
		(11 "B.Adhes" user "B.Adhesive")
		(13 "F.Paste" user "Package Geometry/Pastemask Top")
		(15 "B.Paste" user "Package Geometry/Pastemask Bottom")
		(5 "F.SilkS" user "Ref Des/Silkscreen Top")
		(7 "B.SilkS" user "Ref Des/Silkscreen Bottom")
		(1 "F.Mask" user "Board Geometry/Soldermask Top")
		(3 "B.Mask" user "Board Geometry/Soldermask Bottom")
		(17 "Dwgs.User" user "User.Drawings")
		(19 "Cmts.User" user "User.Comments")
		(21 "Eco1.User" user "User.Eco1")
		(23 "Eco2.User" user "User.Eco2")
		(25 "Edge.Cuts" user "Board Geometry/Outline")
		(27 "Margin" user)
		(31 "F.CrtYd" user "Package Geometry/Place Bound Top")
		(29 "B.CrtYd" user "Package Geometry/Place Bound Bottom")
		(35 "F.Fab" user "Ref Des/Assembly Top")
		(33 "B.Fab" user "Ref Des/Assembly Bottom")
	)
	(footprint ""
		(layer "F.Cu")
		(at 102.354126 -412.578296 90)
		(property "Reference" "R6862"
			(at 0 0 90)
			(layer "F.SilkS")
			(hide yes)
			(effects
				(font
					(size 1.27 1.27)
				)
			)
		)
		(property "Value" ""
			(at 0 0 90)
			(layer "F.Fab")
			(effects
				(font
					(size 1.27 1.27)
				)
			)
		)
		(duplicate_pad_numbers_are_jumpers no)
		(fp_line
			(start 0.7874 -0.4064)
			(end 0.7874 0.4064)
			(stroke
				(width 0.1524)
				(type default)
			)
			(layer "F.SilkS")
		)
		(fp_line
			(start -0.7874 -0.4064)
			(end 0.7874 -0.4064)
			(stroke
				(width 0.1524)
				(type default)
			)
			(layer "F.SilkS")
		)
		(fp_line
			(start 0.7874 0.4064)
			(end -0.7874 0.4064)
			(stroke
				(width 0.1524)
				(type default)
			)
			(layer "F.SilkS")
		)
		(fp_line
			(start -0.7874 0.4064)
			(end -0.7874 -0.4064)
			(stroke
				(width 0.1524)
				(type default)
			)
			(layer "F.SilkS")
		)
		(fp_line
			(start -0.12065 -0.305054)
			(end -0.12065 -0.2794)
			(stroke
				(width 0.1)
				(type default)
			)
			(layer "F.Fab")
		)
		(fp_line
			(start -0.67945 -0.305054)
			(end -0.12065 -0.305054)
			(stroke
				(width 0.1)
				(type default)
			)
			(layer "F.Fab")
		)
		(fp_line
			(start 0.67945 -0.3048)
			(end 0.67945 0.3048)
			(stroke
				(width 0.1)
				(type default)
			)
			(layer "F.Fab")
		)
		(fp_line
			(start 0.12065 -0.3048)
			(end 0.67945 -0.3048)
			(stroke
				(width 0.1)
				(type default)
			)
			(layer "F.Fab")
		)
		(fp_line
			(start 0.12065 -0.2794)
			(end 0.12065 -0.3048)
			(stroke
				(width 0.1)
				(type default)
			)
			(layer "F.Fab")
		)
		(fp_line
			(start -0.12065 -0.2794)
			(end 0.12065 -0.2794)
			(stroke
				(width 0.1)
				(type default)
			)
			(layer "F.Fab")
		)
		(fp_line
			(start 0.120396 0.2794)
			(end -0.12065 0.2794)
			(stroke
				(width 0.1)
				(type default)
			)
			(layer "F.Fab")
		)
		(fp_line
			(start -0.12065 0.2794)
			(end -0.12065 0.3048)
			(stroke
				(width 0.1)
				(type default)
			)
			(layer "F.Fab")
		)
		(fp_line
			(start 0.67945 0.3048)
			(end 0.120396 0.3048)
			(stroke
				(width 0.1)
				(type default)
			)
			(layer "F.Fab")
		)
		(fp_line
			(start 0.120396 0.3048)
			(end 0.120396 0.2794)
			(stroke
				(width 0.1)
				(type default)
			)
			(layer "F.Fab")
		)
		(fp_line
			(start -0.12065 0.3048)
			(end -0.67945 0.3048)
			(stroke
				(width 0.1)
				(type default)
			)
			(layer "F.Fab")
		)
		(fp_line
			(start -0.67945 0.3048)
			(end -0.67945 -0.305054)
			(stroke
				(width 0.1)
				(type default)
			)
			(layer "F.Fab")
		)
		(pad "1" smd circle
			(at -0.40005 0 90)
			(size 0 0)
			(layers "F.Cu" "F.Mask" "F.Paste")
			(net "SMB_HOST_CLK_3V3AUX_SCL_R1")
		)
		(pad "2" smd circle
			(at 0.40005 0 90)
			(size 0 0)
			(layers "F.Cu" "F.Mask" "F.Paste")
			(net "SMB_9ZXL045_P1_SCL")
		)
	)
	(footprint ""
		(layer "F.Cu")
		(at 43.543982 -386.684774 -90)
		(property "Reference" "R627"
			(at 0 0 270)
			(layer "F.SilkS")
			(hide yes)
			(effects
				(font
					(size 1.27 1.27)
				)
			)
		)
		(property "Value" ""
			(at 0 0 270)
			(layer "F.Fab")
			(effects
				(font
					(size 1.27 1.27)
				)
			)
		)
		(duplicate_pad_numbers_are_jumpers no)
		(fp_line
			(start -0.32512 0.175006)
			(end -0.32512 -0.175006)
			(stroke
				(width 0.1)
				(type default)
			)
			(layer "F.Fab")
		)
		(fp_line
			(start 0.32512 0.175006)
			(end -0.32512 0.175006)
			(stroke
				(width 0.1)
				(type default)
			)
			(layer "F.Fab")
		)
		(fp_line
			(start -0.32512 -0.175006)
			(end 0.32512 -0.175006)
			(stroke
				(width 0.1)
				(type default)
			)
			(layer "F.Fab")
		)
		(fp_line
			(start 0.32512 -0.175006)
			(end 0.32512 0.175006)
			(stroke
				(width 0.1)
				(type default)
			)
			(layer "F.Fab")
		)
		(pad "1" smd rect
			(at -0.2667 0 270)
			(size 0.3048 0.381)
			(layers "F.Cu" "F.Mask" "F.Paste")
			(net "CLK_100M_RETIMER_CPU1_P0_DN")
		)
		(pad "2" smd rect
			(at 0.2667 0 90)
			(size 0.3048 0.381)
			(layers "F.Cu" "F.Mask" "F.Paste")
			(net "GND")
		)
	)
)
